FILE_TYPE = CONNECTIVITY;
{Allegro Design Entry HDL 17.2-2016 S081 (4005846) 1/11/2022}
"PAGE_NUMBER" = 188;
0"NC";
1"GND\g";
2"GND\g";
3"GND\g";
4"GND\g";
5"GND\g";
6"GND\g";
7"GND\g";
8"GND\g";
9"GND\g";
10"GND\g";
11"SW_PVDDCR_CPU0_P1_PH6";
12"SW_PVDDCR_CPU0_P1_SW6";
13"GND\g";
14"IND_CPU0_P1_CPL5";
15"IND_CPU0_P1_CPL6";
16"SW_PVDDCR_CPU0_P1_BOOT5_RC";
17"SW_PVDDCR_CPU0_P1_PH5";
18"PVDDCR_CPU0_P1\g";
19"GND\g";
20"PVDDCR_CPU0_P1\g";
21"IND_CPU0_P1_CPL6";
22"SW_PVDDCR_CPU0_P1_BOOT6_RC";
23"IND_CPU0_P1_CPL0";
24"GND\g";
25"SW_PVDDCR_CPU0_P1_SW5";
26"GND\g";
27"SW_PVDDCR_CPU0_P1_BOOT5";
28"SW_P12V_STBY_PVDDCR_CPU0_P1_FLT\g";
29"NC_PVDDCR_CPU0_P1_GL2_5";
30"NC_PVDDCR_CPU0_P1_GL1_5";
31"NC_PVDDCR_CPU0_P1_DNC5";
32"PVDDCR_CPU0_P1_IMON5";
33"PVDDCR_CPU0_P1_TEMP0";
34"PVDDCR_CPU0_P1_LSET5";
35"PVDDCR_CPU0_P1_VCCS";
36"PVDDCR_CPU0_P1_VCC5";
37"PVDDCR_CPU0_P1_PVCC\g";
38"GND\g";
39"PVDDCR_CPU0_P1_VOS5";
40"SW_PVDDCR_CPU0_P1_SW5_RC";
41"GND\g";
42"SW_PVDDCR_CPU0_P1_BOOT6";
43"SW_P12V_STBY_PVDDCR_CPU0_P1_FLT\g";
44"SW_PVDDCR_CPU0_P1_SW6_RC";
45"GND\g";
46"NC_PVDDCR_CPU0_P1_GL1_6";
47"PVDDCR_CPU0_P1_PWM5";
48"PVDDCR_CPU0_P1_PVCC\g";
49"PVDDCR_CPU0_P1_PWM6";
50"PVDDCR_CPU0_P1_TEMP0";
51"PVDDCR_CPU0_P1_IMON6";
52"NC_PVDDCR_CPU0_P1_DNC6";
53"PVDDCR_CPU0_P1_LSET6";
54"NC_PVDDCR_CPU0_P1_GL2_6";
55"PVDDCR_CPU0_P1_VCC6";
56"PVDDCR_CPU0_P1_VCCS";
57"PVDDCR_CPU0_P1_VOS6";
%"UNIVERSAL_GND"
"1","(-7925,4100)","0","pure_quanta_power","I1";
;
CDS_LIB"pure_quanta_power"
HDL_POWER"GND";
"A"1;
%"Q_RES"
"1","(-7275,4350)","0","pure_quanta","I11";
;
LOCATION"PR202"
$SEC"1"
CDS_SEC"1"
WATTAGE"1/16W"
MATERIAL"EMPTY"
TOLERANCE"1%"
VALUE"8.87K"
PART_NUMBER"CS28872FB01"
PACK_TYPE"0402LF"
CDS_LIB"pure_quanta";
"B"
$PN"2"34;
"A"
$PN"1"4;
%"UNIVERSAL_GND"
"1","(-5550,3925)","0","pure_quanta_power","I15";
;
CDS_LIB"pure_quanta_power"
HDL_POWER"GND";
"A"38;
%"Q_RES"
"1","(-4325,3550)","0","pure_quanta","I17";
;
LOCATION"PR204"
$SEC"1"
CDS_SEC"1"
WATTAGE"1/16W"
MATERIAL"CHIP"
TOLERANCE"5%"
VALUE"0"
PART_NUMBER"CS00002JB38"
PACK_TYPE"0402LF"
CDS_LIB"pure_quanta";
"B"
$PN"2"18;
"A"
$PN"1"39;
%"Q_RES"
"1","(-4700,5000)","0","pure_quanta","I18";
;
LOCATION"PR203"
$SEC"1"
CDS_SEC"1"
PACK_TYPE"0402LF"
TOLERANCE"1%"
MATERIAL"CHIP"
WATTAGE"1/16W"
VALUE"4.7"
PART_NUMBER"CS-4702FB19"
CDS_LIB"pure_quanta";
"B"
$PN"2"16;
"A"
$PN"1"27;
%"Q_CAP"
"1","(-4975,5525)","0","pure_quanta","I19";
;
LOCATION"PC310_5"
$SEC"1"
CDS_SEC"1"
MATERIAL"X6S"
TOLERANCE"10%"
VALUE"1UF"
PART_NUMBER"CH5104KEB02"
VOLTAGE"25V"
PACK_TYPE"C0402"
CDS_LIB"pure_quanta";
"B"
$PN"2"26;
"A"
$PN"1"28;
%"Q_CAP"
"1","(-7925,4375)","0","pure_quanta","I2";
;
LOCATION"PC306_5"
$SEC"1"
CDS_SEC"1"
MATERIAL"X7R"
TOLERANCE"10%"
VALUE"0.1UF"
PART_NUMBER"CH4104K1B00"
VOLTAGE"25V"
PACK_TYPE"0402"
CDS_LIB"pure_quanta";
"B"
$PN"2"1;
"A"
$PN"1"35;
%"Q_CAP"
"1","(-4650,5525)","0","pure_quanta","I20";
;
LOCATION"PC311_5"
$SEC"1"
CDS_SEC"1"
MATERIAL"X6S"
TOLERANCE"10%"
VALUE"10UF"
PART_NUMBER"CH6104KEA00"
VOLTAGE"25V"
PACK_TYPE"C0805"
CDS_LIB"pure_quanta";
"B"
$PN"2"26;
"A"
$PN"1"28;
%"Q_CAP"
"1","(-4325,5525)","0","pure_quanta","I21";
;
LOCATION"PC312_5"
$SEC"1"
CDS_SEC"1"
MATERIAL"X6S"
TOLERANCE"10%"
VALUE"10UF"
PART_NUMBER"CH6104KEA00"
VOLTAGE"25V"
PACK_TYPE"C0805"
CDS_LIB"pure_quanta";
"B"
$PN"2"26;
"A"
$PN"1"28;
%"Q_INDUCTOR4P_14"
"1","(-2875,4525)","0","pure_quanta","I23";
;
LOCATION"PL33"
$SEC"1"
CDS_SEC"1"
PART_TYPE"SMLF"
MATERIAL"IND"
VALUE"150NH"
PART_NUMBER"CV+15^0TZ04"
CDS_LIB"pure_quanta"
NEEDS_NO_SIZE"TRUE";
"1"
$PN"1"25;
"4"
$PN"4"18;
"3"
$PN"3"14;
"2"
$PN"2"15;
%"UNIVERSAL_GND"
"1","(-4025,5175)","0","pure_quanta_power","I24";
;
CDS_LIB"pure_quanta_power"
HDL_POWER"GND";
"A"26;
%"Q_CAP"
"1","(-4025,5525)","0","pure_quanta","I25";
;
LOCATION"PC313_5"
$SEC"1"
CDS_SEC"1"
MATERIAL"X6S"
TOLERANCE"10%"
VALUE"10UF"
PART_NUMBER"CH6104KEA00"
VOLTAGE"25V"
PACK_TYPE"C0805"
CDS_LIB"pure_quanta";
"B"
$PN"2"26;
"A"
$PN"1"28;
%"VCC_CORE"
"1","(-4025,5825)","0","pure_quanta_power","I26";
;
HDL_POWER"SW_P12V_STBY_PVDDCR_CPU0_P1_FLT"
CDS_LIB"pure_quanta_power";
"A"28;
%"Q_CAP"
"1","(-1575,4475)","0","pure_quanta","I30";
;
LOCATION"PC315_5"
$SEC"1"
CDS_SEC"1"
MATERIAL"X6S"
TOLERANCE"20%"
VALUE"22UF"
PART_NUMBER"TMP_QCH622KMEA01"
VOLTAGE"4V"
PACK_TYPE"0805"
CDS_LIB"pure_quanta";
"B"
$PN"2"13;
"A"
$PN"1"18;
%"UNIVERSAL_GND"
"1","(-1150,4125)","0","pure_quanta_power","I31";
;
CDS_LIB"pure_quanta_power"
HDL_POWER"GND";
"A"13;
%"Q_CAP"
"1","(-1150,4475)","0","pure_quanta","I32";
;
LOCATION"PC316_5"
$SEC"1"
CDS_SEC"1"
MATERIAL"X6S"
TOLERANCE"20%"
VALUE"22UF"
PART_NUMBER"TMP_QCH622KMEA01"
VOLTAGE"4V"
PACK_TYPE"0805"
CDS_LIB"pure_quanta";
"B"
$PN"2"13;
"A"
$PN"1"18;
%"VCC_CORE"
"1","(-1150,4800)","0","pure_quanta_power","I33";
;
HDL_POWER"PVDDCR_CPU0_P1"
CDS_LIB"pure_quanta_power";
"A"18;
%"ISL99390FRZTR5935"
"1","(-6100,4650)","0","pure_quanta","I35";
;
LOCATION"PU29"
$SEC"1"
CDS_SEC"1"
PART_TYPE"SMLF"
MATERIAL"IC"
VALUE"ISL99390FRZ-TR5935"
PART_NUMBER"AL099390004"
CDS_LIB"pure_quanta"
NEEDS_NO_SIZE"TRUE"
CDS_LMAN_SYM_OUTLINE"-300,700,250,-650";
"PGND2"
$PN"7_9-20_24"38;
"GL2"
$PN"41"29;
"GL1"
$PN"6"30;
"DNC"
$PN"31"31;
"EN"
$PN"35"36;
"PGND3"
$PN"40"38;
"VOS"
$PN"1"39;
"VIN2"
$PN"30"28;
"PGND1"
$PN"5"38;
"SW"
$PN"10_19"25;
"LSET"
$PN"37"34;
"IOUT"
$PN"38"32;
"TOUT_FLT"
$PN"36"33;
"PVCC"
$PN"4"37;
"PHASE"
$PN"32"17;
"VIN1"
$PN"25_29"28;
"BOOT"
$PN"33"27;
"AGND"
$PN"2"38;
"VCC"
$PN"3"36;
"REFIN"
$PN"39"35;
"PWM"
$PN"34"47;
%"Q_CAP"
"1","(-5350,5525)","0","pure_quanta","I36";
;
LOCATION"PC309_5"
$SEC"1"
CDS_SEC"1"
MATERIAL"X7R"
TOLERANCE"10%"
VALUE"0.1UF"
PART_NUMBER"CH4104K1B00"
VOLTAGE"25V"
PACK_TYPE"0402"
CDS_LIB"pure_quanta";
"B"
$PN"2"26;
"A"
$PN"1"28;
%"Q_CAP"
"1","(-7600,5000)","0","pure_quanta","I37";
;
LOCATION"PC307"
$SEC"1"
CDS_SEC"1"
MATERIAL"X6S"
TOLERANCE"10%"
VALUE"2.2UF"
PART_NUMBER"CH5222KEB01"
VOLTAGE"10V"
PACK_TYPE"C0402"
CDS_LIB"pure_quanta";
"B"
$PN"2"2;
"A"
$PN"1"36;
%"UNIVERSAL_GND"
"1","(-7600,4800)","0","pure_quanta_power","I38";
;
CDS_LIB"pure_quanta_power"
HDL_POWER"GND";
"A"2;
%"UNIVERSAL_GND"
"1","(-7250,5300)","0","pure_quanta_power","I39";
;
CDS_LIB"pure_quanta_power"
HDL_POWER"GND";
"A"3;
%"Q_RES"
"2","(-7600,5550)","0","pure_quanta","I40";
;
LOCATION"PR201"
$SEC"1"
CDS_SEC"1"
WATTAGE"1/16W"
MATERIAL"CHIP"
TOLERANCE"1%"
VALUE"2.2"
PART_NUMBER"CS-2202FB00"
PACK_TYPE"0402LF"
CDS_LIB"pure_quanta";
"A"
$PN"1"37;
"B"
$PN"2"36;
%"Q_CAP"
"1","(-7250,5575)","0","pure_quanta","I41";
;
LOCATION"PC308_C0P1_5"
$SEC"1"
CDS_SEC"1"
MATERIAL"X6S"
TOLERANCE"10%"
VALUE"2.2UF"
PART_NUMBER"CH5222KEB01"
VOLTAGE"10V"
PACK_TYPE"C0402"
CDS_LIB"pure_quanta";
"B"
$PN"2"3;
"A"
$PN"1"37;
%"VCC_CORE"
"1","(-7600,5950)","0","pure_quanta_power","I42";
;
HDL_POWER"PVDDCR_CPU0_P1_PVCC"
CDS_LIB"pure_quanta_power";
"A"37;
%"ISL99390FRZTR5935"
"1","(-6050,1750)","0","pure_quanta","I43";
;
LOCATION"PU24"
$SEC"1"
CDS_SEC"1"
PART_TYPE"SMLF"
MATERIAL"IC"
VALUE"ISL99390FRZ-TR5935"
PART_NUMBER"AL099390004"
CDS_LIB"pure_quanta"
NEEDS_NO_SIZE"TRUE"
CDS_LMAN_SYM_OUTLINE"-300,700,250,-650";
"PGND2"
$PN"7_9-20_24"45;
"GL2"
$PN"41"54;
"GL1"
$PN"6"46;
"DNC"
$PN"31"52;
"EN"
$PN"35"55;
"PGND3"
$PN"40"45;
"VOS"
$PN"1"57;
"VIN2"
$PN"30"43;
"PGND1"
$PN"5"45;
"SW"
$PN"10_19"12;
"LSET"
$PN"37"53;
"IOUT"
$PN"38"51;
"TOUT_FLT"
$PN"36"50;
"PVCC"
$PN"4"48;
"PHASE"
$PN"32"11;
"VIN1"
$PN"25_29"43;
"BOOT"
$PN"33"42;
"AGND"
$PN"2"45;
"VCC"
$PN"3"55;
"REFIN"
$PN"39"56;
"PWM"
$PN"34"49;
%"VCC_CORE"
"1","(-1100,1900)","0","pure_quanta_power","I44";
;
HDL_POWER"PVDDCR_CPU0_P1"
CDS_LIB"pure_quanta_power";
"A"20;
%"Q_CAP"
"1","(-1100,1575)","0","pure_quanta","I45";
;
LOCATION"PC135_6"
$SEC"1"
CDS_SEC"1"
MATERIAL"X6S"
TOLERANCE"20%"
VALUE"22UF"
PART_NUMBER"TMP_QCH622KMEA01"
VOLTAGE"4V"
PACK_TYPE"0805"
CDS_LIB"pure_quanta";
"B"
$PN"2"19;
"A"
$PN"1"20;
%"UNIVERSAL_GND"
"1","(-1100,1225)","0","pure_quanta_power","I46";
;
CDS_LIB"pure_quanta_power"
HDL_POWER"GND";
"A"19;
%"Q_CAP"
"1","(-1525,1575)","0","pure_quanta","I47";
;
LOCATION"PC134_6"
$SEC"1"
CDS_SEC"1"
MATERIAL"X6S"
TOLERANCE"20%"
VALUE"22UF"
PART_NUMBER"TMP_QCH622KMEA01"
VOLTAGE"4V"
PACK_TYPE"0805"
CDS_LIB"pure_quanta";
"B"
$PN"2"19;
"A"
$PN"1"20;
%"VCC_CORE"
"1","(-3975,2925)","0","pure_quanta_power","I49";
;
HDL_POWER"SW_P12V_STBY_PVDDCR_CPU0_P1_FLT"
CDS_LIB"pure_quanta_power";
"A"43;
%"UNIVERSAL_GND"
"1","(-7600,4175)","0","pure_quanta_power","I5";
;
CDS_LIB"pure_quanta_power"
HDL_POWER"GND";
"A"4;
%"Q_CAP"
"1","(-3975,2625)","0","pure_quanta","I50";
;
LOCATION"PC132_6"
$SEC"1"
CDS_SEC"1"
MATERIAL"X6S"
TOLERANCE"10%"
VALUE"10UF"
PART_NUMBER"CH6104KEA00"
VOLTAGE"25V"
PACK_TYPE"C0805"
CDS_LIB"pure_quanta";
"B"
$PN"2"41;
"A"
$PN"1"43;
%"UNIVERSAL_GND"
"1","(-3975,2275)","0","pure_quanta_power","I51";
;
CDS_LIB"pure_quanta_power"
HDL_POWER"GND";
"A"41;
%"Q_INDUCTOR4P_14"
"1","(-2825,1625)","0","pure_quanta","I52";
;
LOCATION"PL8"
$SEC"1"
CDS_SEC"1"
PART_TYPE"SMLF"
MATERIAL"IND"
VALUE"150NH"
PART_NUMBER"CV+15^0TZ04"
NEEDS_NO_SIZE"TRUE"
CDS_LIB"pure_quanta";
"1"
$PN"1"12;
"4"
$PN"4"20;
"3"
$PN"3"21;
"2"
$PN"2"23;
%"Q_CAP"
"1","(-3675,1975)","0","pure_quanta","I53";
;
LOCATION"PC133"
$SEC"1"
CDS_SEC"1"
MATERIAL"X7R"
TOLERANCE"10%"
VALUE"0.22UF"
PART_NUMBER"CH4223K1B00"
VOLTAGE"16V"
PACK_TYPE"0402"
CDS_LIB"pure_quanta";
"B"
$PN"2"11;
"A"
$PN"1"22;
%"Q_CAP"
"1","(-4275,2625)","0","pure_quanta","I55";
;
LOCATION"PC130_6"
$SEC"1"
CDS_SEC"1"
MATERIAL"X6S"
TOLERANCE"10%"
VALUE"10UF"
PART_NUMBER"CH6104KEA00"
VOLTAGE"25V"
PACK_TYPE"C0805"
CDS_LIB"pure_quanta";
"B"
$PN"2"41;
"A"
$PN"1"43;
%"Q_CAP"
"1","(-4600,2625)","0","pure_quanta","I56";
;
LOCATION"PC129_6"
$SEC"1"
CDS_SEC"1"
MATERIAL"X6S"
TOLERANCE"10%"
VALUE"10UF"
PART_NUMBER"CH6104KEA00"
VOLTAGE"25V"
PACK_TYPE"C0805"
CDS_LIB"pure_quanta";
"B"
$PN"2"41;
"A"
$PN"1"43;
%"Q_CAP"
"1","(-4925,2625)","0","pure_quanta","I57";
;
LOCATION"PC128_6"
$SEC"1"
CDS_SEC"1"
MATERIAL"X6S"
TOLERANCE"10%"
VALUE"1UF"
PART_NUMBER"CH5104KEB02"
VOLTAGE"25V"
PACK_TYPE"C0402"
CDS_LIB"pure_quanta";
"B"
$PN"2"41;
"A"
$PN"1"43;
%"Q_RES"
"1","(-4225,700)","0","pure_quanta","I58";
;
LOCATION"PR425"
$SEC"1"
CDS_SEC"1"
TOLERANCE"5%"
WATTAGE"1/16W"
MATERIAL"CHIP"
VALUE"0"
PART_NUMBER"CS00002JB38"
PACK_TYPE"0402LF"
CDS_LIB"pure_quanta";
"B"
$PN"2"20;
"A"
$PN"1"57;
%"Q_RES"
"1","(-4650,2100)","0","pure_quanta","I59";
;
LOCATION"PR424"
$SEC"1"
CDS_SEC"1"
PACK_TYPE"0402LF"
TOLERANCE"1%"
MATERIAL"CHIP"
WATTAGE"1/16W"
VALUE"4.7"
PART_NUMBER"CS-4702FB19"
CDS_LIB"pure_quanta";
"B"
$PN"2"22;
"A"
$PN"1"42;
%"Q_CAP"
"1","(-5300,2625)","0","pure_quanta","I60";
;
LOCATION"PC127_6"
$SEC"1"
CDS_SEC"1"
MATERIAL"X7R"
TOLERANCE"10%"
VALUE"0.1UF"
PART_NUMBER"CH4104K1B00"
VOLTAGE"25V"
PACK_TYPE"0402"
CDS_LIB"pure_quanta";
"B"
$PN"2"41;
"A"
$PN"1"43;
%"VCC_CORE"
"1","(-7550,3050)","0","pure_quanta_power","I61";
;
HDL_POWER"PVDDCR_CPU0_P1_PVCC"
CDS_LIB"pure_quanta_power";
"A"48;
%"Q_CAP"
"1","(-7200,2675)","0","pure_quanta","I62";
;
LOCATION"PC126_C0P1_6"
$SEC"1"
CDS_SEC"1"
MATERIAL"X6S"
TOLERANCE"10%"
VALUE"2.2UF"
PART_NUMBER"CH5222KEB01"
VOLTAGE"10V"
PACK_TYPE"C0402"
CDS_LIB"pure_quanta";
"B"
$PN"2"5;
"A"
$PN"1"48;
%"UNIVERSAL_GND"
"1","(-7200,2400)","0","pure_quanta_power","I63";
;
CDS_LIB"pure_quanta_power"
HDL_POWER"GND";
"A"5;
%"Q_RES"
"2","(-7550,2650)","0","pure_quanta","I64";
;
LOCATION"PR422"
$SEC"1"
CDS_SEC"1"
WATTAGE"1/16W"
MATERIAL"CHIP"
TOLERANCE"1%"
VALUE"2.2"
PART_NUMBER"CS-2202FB00"
PACK_TYPE"0402LF"
CDS_LIB"pure_quanta";
"A"
$PN"1"48;
"B"
$PN"2"55;
%"Q_CAP"
"1","(-7550,2100)","0","pure_quanta","I66";
;
LOCATION"PC125"
$SEC"1"
CDS_SEC"1"
MATERIAL"X6S"
TOLERANCE"10%"
VALUE"2.2UF"
PART_NUMBER"CH5222KEB01"
VOLTAGE"10V"
PACK_TYPE"C0402"
CDS_LIB"pure_quanta";
"B"
$PN"2"6;
"A"
$PN"1"55;
%"UNIVERSAL_GND"
"1","(-7550,1900)","0","pure_quanta_power","I67";
;
CDS_LIB"pure_quanta_power"
HDL_POWER"GND";
"A"6;
%"Q_RES"
"1","(-7225,1450)","0","pure_quanta","I68";
;
LOCATION"PR423"
$SEC"1"
CDS_SEC"1"
WATTAGE"1/16W"
MATERIAL"EMPTY"
TOLERANCE"1%"
VALUE"8.87K"
PART_NUMBER"CS28872FB01"
PACK_TYPE"0402LF"
CDS_LIB"pure_quanta";
"B"
$PN"2"53;
"A"
$PN"1"7;
%"UNIVERSAL_GND"
"1","(-7550,1275)","0","pure_quanta_power","I70";
;
CDS_LIB"pure_quanta_power"
HDL_POWER"GND";
"A"7;
%"Q_CAP"
"1","(-7875,1475)","0","pure_quanta","I71";
;
LOCATION"PC124_6"
$SEC"1"
CDS_SEC"1"
MATERIAL"X7R"
TOLERANCE"10%"
VALUE"0.1UF"
PART_NUMBER"CH4104K1B00"
VOLTAGE"25V"
PACK_TYPE"0402"
CDS_LIB"pure_quanta";
"B"
$PN"2"8;
"A"
$PN"1"56;
%"UNIVERSAL_GND"
"1","(-5500,1025)","0","pure_quanta_power","I72";
;
CDS_LIB"pure_quanta_power"
HDL_POWER"GND";
"A"45;
%"UNIVERSAL_GND"
"1","(-7875,1200)","0","pure_quanta_power","I74";
;
CDS_LIB"pure_quanta_power"
HDL_POWER"GND";
"A"8;
%"Q_CAP"
"1","(-3725,4875)","0","pure_quanta","I80";
;
LOCATION"PC314"
$SEC"1"
CDS_SEC"1"
MATERIAL"X7R"
TOLERANCE"10%"
VALUE"0.22UF"
PART_NUMBER"CH4223K1B00"
VOLTAGE"16V"
PACK_TYPE"0402"
CDS_LIB"pure_quanta";
"B"
$PN"2"17;
"A"
$PN"1"16;
%"UNIVERSAL_GND"
"1","(-4625,825)","0","pure_quanta_power","I81";
;
CDS_LIB"pure_quanta_power"
HDL_POWER"GND";
"A"9;
%"Q_RES"
"2","(-4625,1050)","0","pure_quanta","I82";
;
LOCATION"PR524"
$SEC"1"
CDS_SEC"1"
PART_NUMBER"CS-1504FB00"
WATTAGE"1/8W"
MATERIAL"EMPTY"
TOLERANCE"1%"
VALUE"1.5"
PACK_TYPE"0402LF"
CDS_LIB"pure_quanta";
"A"
$PN"1"44;
"B"
$PN"2"9;
%"Q_CAP"
"1","(-4625,1550)","0","pure_quanta","I83";
;
LOCATION"PC321"
$SEC"1"
CDS_SEC"1"
PART_NUMBER"CH1566K1B09"
MATERIAL"EMPTY"
TOLERANCE"10%"
VALUE"560PF"
VOLTAGE"50V"
PACK_TYPE"C0402"
CDS_LIB"pure_quanta";
"B"
$PN"2"44;
"A"
$PN"1"12;
%"UNIVERSAL_GND"
"1","(-4675,3700)","0","pure_quanta_power","I84";
;
CDS_LIB"pure_quanta_power"
HDL_POWER"GND";
"A"10;
%"Q_RES"
"2","(-4675,3925)","0","pure_quanta","I85";
;
LOCATION"PR46"
$SEC"1"
CDS_SEC"1"
WATTAGE"1/8W"
MATERIAL"EMPTY"
TOLERANCE"1%"
VALUE"1.5"
PART_NUMBER"CS-1504FB00"
PACK_TYPE"0402LF"
CDS_LIB"pure_quanta";
"A"
$PN"1"40;
"B"
$PN"2"10;
%"Q_CAP"
"1","(-4675,4450)","0","pure_quanta","I86";
;
LOCATION"PC318"
$SEC"1"
CDS_SEC"1"
MATERIAL"EMPTY"
TOLERANCE"10%"
VALUE"560PF"
PART_NUMBER"CH1566K1B09"
VOLTAGE"50V"
PACK_TYPE"C0402"
CDS_LIB"pure_quanta";
"B"
$PN"2"40;
"A"
$PN"1"25;
%"Q_INDUCTOR"
"1","(-3800,1525)","0","pure_quanta","I87";
;
LOCATION"PL27"
$SEC"1"
CDS_SEC"1"
PACK_TYPE"SMLF"
MATERIAL"IND"
VALUE"0.22UH/33A"
PART_NUMBER"CV+22Y0EZ00"
CDS_LIB"pure_quanta"
NEEDS_NO_SIZE"TRUE";
"1"
$PN"1"24;
"2"
$PN"2"23;
%"UNIVERSAL_GND"
"1","(-4100,1375)","0","pure_quanta_power","I88";
;
CDS_LIB"pure_quanta_power"
HDL_POWER"GND";
"A"24;
END.
